# S9S_MB_2U (Grand Teton) — schematic netlist excerpt (pin names and nets, part order shuffled) for the footprints in the layout excerpt that follows; sources: Cadence DE-HDL packaged netlist, KiCad conversion of 03242023_DA0F0TMBIJ0_F0T_Motherboard_J_brd_V01_OCP.brd

C289  Q_CAP  22UF 4V 20% X6S  pkg C0402  page 77 : A = PVCCIN_CPU1 ; B = GND
PC2951  Q_CAP  2.2UF 10V 10% X6S  pkg C0402  page 297 : A = PVCCFA_EHV_CPU1_PVCC ; B = GND

(kicad_pcb
	(version 20260206)
	(generator "pcbnew")
	(generator_version "10.0")
	(general
		(thickness 1.6)
		(legacy_teardrops no)
	)
	(paper "A4")
	(title_block
		(title "03242023_DA0F0TMBIJ0_F0T_Motherboard_J_brd_V01_OCP.brd")
		(comment 1 "Grand Teton / footprints 325-326 of 6105")
	)
	(layers
		(0 "F.Cu" signal "TOP")
		(4 "In1.Cu" signal "GND")
		(6 "In2.Cu" signal "IN1")
		(8 "In3.Cu" signal "GND1")
		(10 "In4.Cu" signal "IN2")
		(12 "In5.Cu" signal "GND2")
		(14 "In6.Cu" signal "IN3")
		(16 "In7.Cu" signal "GND3")
		(18 "In8.Cu" signal "VCC")
		(20 "In9.Cu" signal "VCC1")
		(22 "In10.Cu" signal "GND4")
		(24 "In11.Cu" signal "IN4")
		(26 "In12.Cu" signal "GND5")
		(28 "In13.Cu" signal "IN5")
		(30 "In14.Cu" signal "GND6")
		(32 "In15.Cu" signal "IN6")
		(34 "In16.Cu" signal "GND7")
		(2 "B.Cu" signal "BOTTOM")
		(9 "F.Adhes" user "F.Adhesive")
		(11 "B.Adhes" user "B.Adhesive")
		(13 "F.Paste" user "Package Geometry/Pastemask Top")
		(15 "B.Paste" user "Package Geometry/Pastemask Bottom")
		(5 "F.SilkS" user "Ref Des/Silkscreen Top")
		(7 "B.SilkS" user "Ref Des/Silkscreen Bottom")
		(1 "F.Mask" user "Board Geometry/Soldermask Top")
		(3 "B.Mask" user "Board Geometry/Soldermask Bottom")
		(17 "Dwgs.User" user "User.Drawings")
		(19 "Cmts.User" user "User.Comments")
		(21 "Eco1.User" user "User.Eco1")
		(23 "Eco2.User" user "User.Eco2")
		(25 "Edge.Cuts" user "Board Geometry/Outline")
		(27 "Margin" user)
		(31 "F.CrtYd" user "Package Geometry/Place Bound Top")
		(29 "B.CrtYd" user "Package Geometry/Place Bound Bottom")
		(35 "F.Fab" user "Ref Des/Assembly Top")
		(33 "B.Fab" user "Ref Des/Assembly Bottom")
	)
	(footprint ""
		(layer "F.Cu")
		(at 55.090314 -161.539174)
		(property "Reference" "PC2951"
			(at 0 0 0)
			(layer "F.SilkS")
			(hide yes)
			(effects
				(font
					(size 1.27 1.27)
				)
			)
		)
		(property "Value" ""
			(at 0 0 0)
			(layer "F.Fab")
			(effects
				(font
					(size 1.27 1.27)
				)
			)
		)
		(duplicate_pad_numbers_are_jumpers no)
		(fp_line
			(start -0.7874 -0.4064)
			(end 0.7874 -0.4064)
			(stroke
				(width 0.1524)
				(type default)
			)
			(layer "F.SilkS")
		)
		(fp_line
			(start -0.7874 0.4064)
			(end -0.7874 -0.4064)
			(stroke
				(width 0.1524)
				(type default)
			)
			(layer "F.SilkS")
		)
		(fp_line
			(start 0.7874 -0.4064)
			(end 0.7874 0.4064)
			(stroke
				(width 0.1524)
				(type default)
			)
			(layer "F.SilkS")
		)
		(fp_line
			(start 0.7874 0.4064)
			(end -0.7874 0.4064)
			(stroke
				(width 0.1524)
				(type default)
			)
			(layer "F.SilkS")
		)
		(fp_line
			(start -0.67945 -0.305054)
			(end -0.12065 -0.305054)
			(stroke
				(width 0.1)
				(type default)
			)
			(layer "F.Fab")
		)
		(fp_line
			(start -0.67945 0.3048)
			(end -0.67945 -0.305054)
			(stroke
				(width 0.1)
				(type default)
			)
			(layer "F.Fab")
		)
		(fp_line
			(start -0.12065 -0.305054)
			(end -0.12065 -0.2794)
			(stroke
				(width 0.1)
				(type default)
			)
			(layer "F.Fab")
		)
		(fp_line
			(start -0.12065 -0.2794)
			(end 0.12065 -0.2794)
			(stroke
				(width 0.1)
				(type default)
			)
			(layer "F.Fab")
		)
		(fp_line
			(start -0.12065 0.2794)
			(end -0.12065 0.3048)
			(stroke
				(width 0.1)
				(type default)
			)
			(layer "F.Fab")
		)
		(fp_line
			(start -0.12065 0.3048)
			(end -0.67945 0.3048)
			(stroke
				(width 0.1)
				(type default)
			)
			(layer "F.Fab")
		)
		(fp_line
			(start 0.120396 0.2794)
			(end -0.12065 0.2794)
			(stroke
				(width 0.1)
				(type default)
			)
			(layer "F.Fab")
		)
		(fp_line
			(start 0.120396 0.3048)
			(end 0.120396 0.2794)
			(stroke
				(width 0.1)
				(type default)
			)
			(layer "F.Fab")
		)
		(fp_line
			(start 0.12065 -0.3048)
			(end 0.67945 -0.3048)
			(stroke
				(width 0.1)
				(type default)
			)
			(layer "F.Fab")
		)
		(fp_line
			(start 0.12065 -0.2794)
			(end 0.12065 -0.3048)
			(stroke
				(width 0.1)
				(type default)
			)
			(layer "F.Fab")
		)
		(fp_line
			(start 0.67945 -0.3048)
			(end 0.67945 0.3048)
			(stroke
				(width 0.1)
				(type default)
			)
			(layer "F.Fab")
		)
		(fp_line
			(start 0.67945 0.3048)
			(end 0.120396 0.3048)
			(stroke
				(width 0.1)
				(type default)
			)
			(layer "F.Fab")
		)
		(pad "1" smd circle
			(at -0.40005 0)
			(size 0 0)
			(layers "F.Cu" "F.Mask" "F.Paste")
			(net "PVCCFA_EHV_CPU1_PVCC")
		)
		(pad "2" smd circle
			(at 0.40005 0)
			(size 0 0)
			(layers "F.Cu" "F.Mask" "F.Paste")
			(net "GND")
		)
	)
	(footprint ""
		(layer "F.Cu")
		(at 116.561616 -256.6543 -90)
		(property "Reference" "C289"
			(at 0 0 270)
			(layer "F.SilkS")
			(hide yes)
			(effects
				(font
					(size 1.27 1.27)
				)
			)
		)
		(property "Value" ""
			(at 0 0 270)
			(layer "F.Fab")
			(effects
				(font
					(size 1.27 1.27)
				)
			)
		)
		(duplicate_pad_numbers_are_jumpers no)
		(fp_line
			(start -0.7874 0.4064)
			(end -0.7874 -0.4064)
			(stroke
				(width 0.1524)
				(type default)
			)
			(layer "F.SilkS")
		)
		(fp_line
			(start 0.7874 0.4064)
			(end -0.7874 0.4064)
			(stroke
				(width 0.1524)
				(type default)
			)
			(layer "F.SilkS")
		)
		(fp_line
			(start -0.7874 -0.4064)
			(end 0.7874 -0.4064)
			(stroke
				(width 0.1524)
				(type default)
			)
			(layer "F.SilkS")
		)
		(fp_line
			(start 0.7874 -0.4064)
			(end 0.7874 0.4064)
			(stroke
				(width 0.1524)
				(type default)
			)
			(layer "F.SilkS")
		)
		(fp_line
			(start -0.67945 0.3048)
			(end -0.67945 -0.305054)
			(stroke
				(width 0.1)
				(type default)
			)
			(layer "F.Fab")
		)
		(fp_line
			(start -0.12065 0.3048)
			(end -0.67945 0.3048)
			(stroke
				(width 0.1)
				(type default)
			)
			(layer "F.Fab")
		)
		(fp_line
			(start 0.120396 0.3048)
			(end 0.120396 0.2794)
			(stroke
				(width 0.1)
				(type default)
			)
			(layer "F.Fab")
		)
		(fp_line
			(start 0.67945 0.3048)
			(end 0.120396 0.3048)
			(stroke
				(width 0.1)
				(type default)
			)
			(layer "F.Fab")
		)
		(fp_line
			(start -0.12065 0.2794)
			(end -0.12065 0.3048)
			(stroke
				(width 0.1)
				(type default)
			)
			(layer "F.Fab")
		)
		(fp_line
			(start 0.120396 0.2794)
			(end -0.12065 0.2794)
			(stroke
				(width 0.1)
				(type default)
			)
			(layer "F.Fab")
		)
		(fp_line
			(start -0.12065 -0.2794)
			(end 0.12065 -0.2794)
			(stroke
				(width 0.1)
				(type default)
			)
			(layer "F.Fab")
		)
		(fp_line
			(start 0.12065 -0.2794)
			(end 0.12065 -0.3048)
			(stroke
				(width 0.1)
				(type default)
			)
			(layer "F.Fab")
		)
		(fp_line
			(start 0.12065 -0.3048)
			(end 0.67945 -0.3048)
			(stroke
				(width 0.1)
				(type default)
			)
			(layer "F.Fab")
		)
		(fp_line
			(start 0.67945 -0.3048)
			(end 0.67945 0.3048)
			(stroke
				(width 0.1)
				(type default)
			)
			(layer "F.Fab")
		)
		(fp_line
			(start -0.67945 -0.305054)
			(end -0.12065 -0.305054)
			(stroke
				(width 0.1)
				(type default)
			)
			(layer "F.Fab")
		)
		(fp_line
			(start -0.12065 -0.305054)
			(end -0.12065 -0.2794)
			(stroke
				(width 0.1)
				(type default)
			)
			(layer "F.Fab")
		)
		(pad "1" smd circle
			(at -0.40005 0 270)
			(size 0 0)
			(layers "F.Cu" "F.Mask" "F.Paste")
			(net "PVCCIN_CPU1")
		)
		(pad "2" smd circle
			(at 0.40005 0 270)
			(size 0 0)
			(layers "F.Cu" "F.Mask" "F.Paste")
			(net "GND")
		)
	)
)
